(kicad_pcb
	(version 20260206)
	(generator "pcbnew")
	(generator_version "10.0")
	(general
		(thickness 1.6)
		(legacy_teardrops no)
	)
	(paper "A4")
	(title_block
		(title "01162023_DA0F0TEBIF0_F0T_Expander_BD_F_brd_V02_OCP.brd")
		(comment 1 "Grand Teton / footprints 6082-6087 of 9728")
	)
	(layers
		(0 "F.Cu" signal "TOP")
		(4 "In1.Cu" signal "GND")
		(6 "In2.Cu" signal "VCC")
		(8 "In3.Cu" signal "VCC1")
		(10 "In4.Cu" signal "GND1")
		(12 "In5.Cu" signal "IN1")
		(14 "In6.Cu" signal "GND2")
		(16 "In7.Cu" signal "IN2")
		(18 "In8.Cu" signal "GND3")
		(20 "In9.Cu" signal "IN3")
		(22 "In10.Cu" signal "GND4")
		(24 "In11.Cu" signal "IN4")
		(26 "In12.Cu" signal "GND5")
		(28 "In13.Cu" signal "IN5")
		(30 "In14.Cu" signal "GND6")
		(32 "In15.Cu" signal "IN6")
		(34 "In16.Cu" signal "GND7")
		(2 "B.Cu" signal "BOTTOM")
		(9 "F.Adhes" user "F.Adhesive")
		(11 "B.Adhes" user "B.Adhesive")
		(13 "F.Paste" user "Package Geometry/Pastemask Top")
		(15 "B.Paste" user "Package Geometry/Pastemask Bottom")
		(5 "F.SilkS" user "Ref Des/Silkscreen Top")
		(7 "B.SilkS" user "Ref Des/Silkscreen Bottom")
		(1 "F.Mask" user "Board Geometry/Soldermask Top")
		(3 "B.Mask" user "Board Geometry/Soldermask Bottom")
		(17 "Dwgs.User" user "User.Drawings")
		(19 "Cmts.User" user "User.Comments")
		(21 "Eco1.User" user "User.Eco1")
		(23 "Eco2.User" user "User.Eco2")
		(25 "Edge.Cuts" user "Board Geometry/Outline")
		(27 "Margin" user)
		(31 "F.CrtYd" user "Package Geometry/Place Bound Top")
		(29 "B.CrtYd" user "Package Geometry/Place Bound Bottom")
		(35 "F.Fab" user "Ref Des/Assembly Top")
		(33 "B.Fab" user "Ref Des/Assembly Bottom")
	)
	(footprint ""
		(layer "F.Cu")
		(at 284.443678 -42.84091)
		(property "Reference" "R604"
			(at 0 0 0)
			(layer "F.SilkS")
			(hide yes)
			(effects
				(font
					(size 1.27 1.27)
				)
			)
		)
		(property "Value" ""
			(at 0 0 0)
			(layer "F.Fab")
			(effects
				(font
					(size 1.27 1.27)
				)
			)
		)
		(duplicate_pad_numbers_are_jumpers no)
		(fp_line
			(start -0.7874 -0.4064)
			(end 0.7874 -0.4064)
			(stroke
				(width 0.1524)
				(type default)
			)
			(layer "F.SilkS")
		)
		(fp_line
			(start -0.7874 0.4064)
			(end -0.7874 -0.4064)
			(stroke
				(width 0.1524)
				(type default)
			)
			(layer "F.SilkS")
		)
		(fp_line
			(start 0.7874 -0.4064)
			(end 0.7874 0.4064)
			(stroke
				(width 0.1524)
				(type default)
			)
			(layer "F.SilkS")
		)
		(fp_line
			(start 0.7874 0.4064)
			(end -0.7874 0.4064)
			(stroke
				(width 0.1524)
				(type default)
			)
			(layer "F.SilkS")
		)
		(fp_line
			(start -0.67945 -0.305054)
			(end -0.12065 -0.305054)
			(stroke
				(width 0.1)
				(type default)
			)
			(layer "F.Fab")
		)
		(fp_line
			(start -0.67945 0.3048)
			(end -0.67945 -0.305054)
			(stroke
				(width 0.1)
				(type default)
			)
			(layer "F.Fab")
		)
		(fp_line
			(start -0.12065 -0.305054)
			(end -0.12065 -0.2794)
			(stroke
				(width 0.1)
				(type default)
			)
			(layer "F.Fab")
		)
		(fp_line
			(start -0.12065 -0.2794)
			(end 0.12065 -0.2794)
			(stroke
				(width 0.1)
				(type default)
			)
			(layer "F.Fab")
		)
		(fp_line
			(start -0.12065 0.2794)
			(end -0.12065 0.3048)
			(stroke
				(width 0.1)
				(type default)
			)
			(layer "F.Fab")
		)
		(fp_line
			(start -0.12065 0.3048)
			(end -0.67945 0.3048)
			(stroke
				(width 0.1)
				(type default)
			)
			(layer "F.Fab")
		)
		(fp_line
			(start 0.120396 0.2794)
			(end -0.12065 0.2794)
			(stroke
				(width 0.1)
				(type default)
			)
			(layer "F.Fab")
		)
		(fp_line
			(start 0.120396 0.3048)
			(end 0.120396 0.2794)
			(stroke
				(width 0.1)
				(type default)
			)
			(layer "F.Fab")
		)
		(fp_line
			(start 0.12065 -0.3048)
			(end 0.67945 -0.3048)
			(stroke
				(width 0.1)
				(type default)
			)
			(layer "F.Fab")
		)
		(fp_line
			(start 0.12065 -0.2794)
			(end 0.12065 -0.3048)
			(stroke
				(width 0.1)
				(type default)
			)
			(layer "F.Fab")
		)
		(fp_line
			(start 0.67945 -0.3048)
			(end 0.67945 0.3048)
			(stroke
				(width 0.1)
				(type default)
			)
			(layer "F.Fab")
		)
		(fp_line
			(start 0.67945 0.3048)
			(end 0.120396 0.3048)
			(stroke
				(width 0.1)
				(type default)
			)
			(layer "F.Fab")
		)
		(pad "1" smd circle
			(at -0.40005 0)
			(size 0 0)
			(layers "F.Cu" "F.Mask" "F.Paste")
			(net "SSD9_ADC_A1")
		)
		(pad "2" smd circle
			(at 0.40005 0)
			(size 0 0)
			(layers "F.Cu" "F.Mask" "F.Paste")
			(net "P3V3_AUX")
		)
	)
	(footprint ""
		(layer "F.Cu")
		(at 205.749652 -320.900044)
		(property "Reference" "H84"
			(at -7.150608 -7.090664 0)
			(unlocked yes)
			(layer "F.SilkS")
			(effects
				(font
					(size 0.7874 0.5842)
					(thickness 0.1524)
				)
				(justify left)
			)
		)
		(property "Value" ""
			(at 0 0 0)
			(layer "F.Fab")
			(effects
				(font
					(size 1.27 1.27)
				)
			)
		)
		(duplicate_pad_numbers_are_jumpers no)
		(fp_arc
			(start -7.962138 -0.77724)
			(mid -2.032459 -7.737232)
			(end 6.552184 -4.58978)
			(stroke
				(width 0.1524)
				(type default)
			)
			(layer "F.SilkS")
		)
		(fp_arc
			(start 7.999984 0)
			(mid 3.047385 7.396948)
			(end -5.678424 5.635244)
			(stroke
				(width 0.1524)
				(type default)
			)
			(layer "F.SilkS")
		)
		(fp_arc
			(start -7.981442 0.544068)
			(mid -0.272184 -7.995347)
			(end 7.999984 0)
			(stroke
				(width 0.1524)
				(type default)
			)
			(layer "B.SilkS")
		)
		(fp_arc
			(start 7.999984 0)
			(mid 3.266595 7.302491)
			(end -5.332222 5.963666)
			(stroke
				(width 0.1524)
				(type default)
			)
			(layer "B.SilkS")
		)
		(fp_circle
			(center 0 0)
			(end 7.999984 0)
			(stroke
				(width 0.1)
				(type default)
			)
			(fill no)
			(layer "B.Fab")
		)
		(fp_circle
			(center 0 0)
			(end 7.999984 0)
			(stroke
				(width 0.1)
				(type default)
			)
			(fill no)
			(layer "F.Fab")
		)
		(pad "" np_thru_hole circle
			(at 0 0)
			(size 4.5212 4.5212)
			(drill 4.5212)
			(layers "*.Cu" "*.Mask")
			(clearance 0.381)
			(thermal_gap 0.381)
		)
		(pad "2" thru_hole circle
			(at 3.6322 0)
			(size 0.762 0.762)
			(drill 0.5588)
			(layers "*.Cu" "*.Mask")
			(remove_unused_layers no)
			(net "GND")
			(clearance 0.1524)
			(thermal_gap 0.1524)
		)
		(pad "3" thru_hole circle
			(at 2.568448 -2.568448)
			(size 0.762 0.762)
			(drill 0.5588)
			(layers "*.Cu" "*.Mask")
			(remove_unused_layers no)
			(net "GND")
			(clearance 0.1524)
			(thermal_gap 0.1524)
		)
		(pad "4" thru_hole circle
			(at 0 -3.6322)
			(size 0.762 0.762)
			(drill 0.5588)
			(layers "*.Cu" "*.Mask")
			(remove_unused_layers no)
			(net "GND")
			(clearance 0.1524)
			(thermal_gap 0.1524)
		)
		(pad "5" thru_hole circle
			(at -2.568448 -2.568448)
			(size 0.762 0.762)
			(drill 0.5588)
			(layers "*.Cu" "*.Mask")
			(remove_unused_layers no)
			(net "GND")
			(clearance 0.1524)
			(thermal_gap 0.1524)
		)
		(pad "6" thru_hole circle
			(at -3.6322 0)
			(size 0.762 0.762)
			(drill 0.5588)
			(layers "*.Cu" "*.Mask")
			(remove_unused_layers no)
			(net "GND")
			(clearance 0.1524)
			(thermal_gap 0.1524)
		)
		(pad "7" thru_hole circle
			(at -2.568448 2.568448)
			(size 0.762 0.762)
			(drill 0.5588)
			(layers "*.Cu" "*.Mask")
			(remove_unused_layers no)
			(net "GND")
			(clearance 0.1524)
			(thermal_gap 0.1524)
		)
		(pad "8" thru_hole circle
			(at 0 3.6322)
			(size 0.762 0.762)
			(drill 0.5588)
			(layers "*.Cu" "*.Mask")
			(remove_unused_layers no)
			(net "GND")
			(clearance 0.1524)
			(thermal_gap 0.1524)
		)
		(pad "9" thru_hole circle
			(at 2.568448 2.568448)
			(size 0.762 0.762)
			(drill 0.5588)
			(layers "*.Cu" "*.Mask")
			(remove_unused_layers no)
			(net "GND")
			(clearance 0.1524)
			(thermal_gap 0.1524)
		)
		(zone
			(layer "F.Cu")
			(hatch none 0.5)
			(connect_pads
				(clearance 0)
			)
			(min_thickness 0.25)
			(keepout
				(tracks not_allowed)
				(vias allowed)
				(pads allowed)
				(copperpour not_allowed)
				(footprints allowed)
			)
			(placement
				(enabled no)
				(sheetname "")
			)
			(fill
				(thermal_gap 0.5)
				(thermal_bridge_width 0.5)
				(island_removal_mode 0)
			)
			(polygon
				(pts
					(arc
						(start 205.749652 -312.90006)
						(mid 197.749668 -320.900044)
						(end 205.749652 -328.900028)
					)
					(arc
						(start 205.749652 -325.649844)
						(mid 200.999852 -320.900044)
						(end 205.749652 -316.150244)
					)
				)
			)
		)
		(zone
			(layer "F.Cu")
			(hatch none 0.5)
			(connect_pads
				(clearance 0)
			)
			(min_thickness 0.25)
			(keepout
				(tracks not_allowed)
				(vias allowed)
				(pads allowed)
				(copperpour not_allowed)
				(footprints allowed)
			)
			(placement
				(enabled no)
				(sheetname "")
			)
			(fill
				(thermal_gap 0.5)
				(thermal_bridge_width 0.5)
				(island_removal_mode 0)
			)
			(polygon
				(pts
					(arc
						(start 205.749652 -312.90006)
						(mid 213.749636 -320.900044)
						(end 205.749652 -328.900028)
					)
					(arc
						(start 205.749652 -325.649844)
						(mid 210.499452 -320.900044)
						(end 205.749652 -316.150244)
					)
				)
			)
		)
		(zone
			(layers "F.Cu" "B.Cu" "In1.Cu" "In2.Cu" "In3.Cu" "In4.Cu" "In5.Cu" "In6.Cu"
				"In7.Cu" "In8.Cu" "In9.Cu" "In10.Cu" "In11.Cu" "In12.Cu" "In13.Cu" "In14.Cu"
				"In15.Cu" "In16.Cu"
			)
			(hatch none 0.5)
			(connect_pads
				(clearance 0)
			)
			(min_thickness 0.25)
			(keepout
				(tracks not_allowed)
				(vias allowed)
				(pads allowed)
				(copperpour not_allowed)
				(footprints allowed)
			)
			(placement
				(enabled no)
				(sheetname "")
			)
			(fill
				(thermal_gap 0.5)
				(thermal_bridge_width 0.5)
				(island_removal_mode 0)
			)
			(polygon
				(pts
					(arc
						(start 208.515712 -320.900044)
						(mid 202.983592 -320.900044)
						(end 208.515712 -320.900044)
					)
				)
			)
		)
		(zone
			(layer "B.Cu")
			(hatch none 0.5)
			(connect_pads
				(clearance 0)
			)
			(min_thickness 0.25)
			(keepout
				(tracks not_allowed)
				(vias allowed)
				(pads allowed)
				(copperpour not_allowed)
				(footprints allowed)
			)
			(placement
				(enabled no)
				(sheetname "")
			)
			(fill
				(thermal_gap 0.5)
				(thermal_bridge_width 0.5)
				(island_removal_mode 0)
			)
			(polygon
				(pts
					(arc
						(start 205.749652 -315.896244)
						(mid 200.745852 -320.900044)
						(end 205.749652 -325.903844)
					)
					(arc
						(start 205.749652 -325.421244)
						(mid 201.228452 -320.900044)
						(end 205.749652 -316.378844)
					)
				)
			)
		)
		(zone
			(layer "B.Cu")
			(hatch none 0.5)
			(connect_pads
				(clearance 0)
			)
			(min_thickness 0.25)
			(keepout
				(tracks not_allowed)
				(vias allowed)
				(pads allowed)
				(copperpour not_allowed)
				(footprints allowed)
			)
			(placement
				(enabled no)
				(sheetname "")
			)
			(fill
				(thermal_gap 0.5)
				(thermal_bridge_width 0.5)
				(island_removal_mode 0)
			)
			(polygon
				(pts
					(arc
						(start 205.749652 -315.896244)
						(mid 210.753452 -320.900044)
						(end 205.749652 -325.903844)
					)
					(arc
						(start 205.749652 -325.421244)
						(mid 210.270852 -320.900044)
						(end 205.749652 -316.378844)
					)
				)
			)
		)
	)
	(footprint ""
		(layer "F.Cu")
		(at 214.310976 -371.337586)
		(property "Reference" "PR28"
			(at 0 0 0)
			(layer "F.SilkS")
			(hide yes)
			(effects
				(font
					(size 1.27 1.27)
				)
			)
		)
		(property "Value" ""
			(at 0 0 0)
			(layer "F.Fab")
			(effects
				(font
					(size 1.27 1.27)
				)
			)
		)
		(duplicate_pad_numbers_are_jumpers no)
		(fp_line
			(start -0.7874 -0.4064)
			(end 0.7874 -0.4064)
			(stroke
				(width 0.1524)
				(type default)
			)
			(layer "F.SilkS")
		)
		(fp_line
			(start -0.7874 0.4064)
			(end -0.7874 -0.4064)
			(stroke
				(width 0.1524)
				(type default)
			)
			(layer "F.SilkS")
		)
		(fp_line
			(start 0.7874 -0.4064)
			(end 0.7874 0.4064)
			(stroke
				(width 0.1524)
				(type default)
			)
			(layer "F.SilkS")
		)
		(fp_line
			(start 0.7874 0.4064)
			(end -0.7874 0.4064)
			(stroke
				(width 0.1524)
				(type default)
			)
			(layer "F.SilkS")
		)
		(fp_line
			(start -0.67945 -0.305054)
			(end -0.12065 -0.305054)
			(stroke
				(width 0.1)
				(type default)
			)
			(layer "F.Fab")
		)
		(fp_line
			(start -0.67945 0.3048)
			(end -0.67945 -0.305054)
			(stroke
				(width 0.1)
				(type default)
			)
			(layer "F.Fab")
		)
		(fp_line
			(start -0.12065 -0.305054)
			(end -0.12065 -0.2794)
			(stroke
				(width 0.1)
				(type default)
			)
			(layer "F.Fab")
		)
		(fp_line
			(start -0.12065 -0.2794)
			(end 0.12065 -0.2794)
			(stroke
				(width 0.1)
				(type default)
			)
			(layer "F.Fab")
		)
		(fp_line
			(start -0.12065 0.2794)
			(end -0.12065 0.3048)
			(stroke
				(width 0.1)
				(type default)
			)
			(layer "F.Fab")
		)
		(fp_line
			(start -0.12065 0.3048)
			(end -0.67945 0.3048)
			(stroke
				(width 0.1)
				(type default)
			)
			(layer "F.Fab")
		)
		(fp_line
			(start 0.120396 0.2794)
			(end -0.12065 0.2794)
			(stroke
				(width 0.1)
				(type default)
			)
			(layer "F.Fab")
		)
		(fp_line
			(start 0.120396 0.3048)
			(end 0.120396 0.2794)
			(stroke
				(width 0.1)
				(type default)
			)
			(layer "F.Fab")
		)
		(fp_line
			(start 0.12065 -0.3048)
			(end 0.67945 -0.3048)
			(stroke
				(width 0.1)
				(type default)
			)
			(layer "F.Fab")
		)
		(fp_line
			(start 0.12065 -0.2794)
			(end 0.12065 -0.3048)
			(stroke
				(width 0.1)
				(type default)
			)
			(layer "F.Fab")
		)
		(fp_line
			(start 0.67945 -0.3048)
			(end 0.67945 0.3048)
			(stroke
				(width 0.1)
				(type default)
			)
			(layer "F.Fab")
		)
		(fp_line
			(start 0.67945 0.3048)
			(end 0.120396 0.3048)
			(stroke
				(width 0.1)
				(type default)
			)
			(layer "F.Fab")
		)
		(pad "1" smd circle
			(at -0.40005 0)
			(size 0 0)
			(layers "F.Cu" "F.Mask" "F.Paste")
			(net "HSC_SCREF")
		)
		(pad "2" smd circle
			(at 0.40005 0)
			(size 0 0)
			(layers "F.Cu" "F.Mask" "F.Paste")
			(net "HSC_SCREF_1")
		)
	)
	(footprint ""
		(layer "F.Cu")
		(at 251.671582 -25.342342 -90)
		(property "Reference" "R433"
			(at 0 0 270)
			(layer "F.SilkS")
			(hide yes)
			(effects
				(font
					(size 1.27 1.27)
				)
			)
		)
		(property "Value" ""
			(at 0 0 270)
			(layer "F.Fab")
			(effects
				(font
					(size 1.27 1.27)
				)
			)
		)
		(duplicate_pad_numbers_are_jumpers no)
		(fp_line
			(start -0.7874 0.4064)
			(end -0.7874 -0.4064)
			(stroke
				(width 0.1524)
				(type default)
			)
			(layer "F.SilkS")
		)
		(fp_line
			(start 0.7874 0.4064)
			(end -0.7874 0.4064)
			(stroke
				(width 0.1524)
				(type default)
			)
			(layer "F.SilkS")
		)
		(fp_line
			(start -0.7874 -0.4064)
			(end 0.7874 -0.4064)
			(stroke
				(width 0.1524)
				(type default)
			)
			(layer "F.SilkS")
		)
		(fp_line
			(start 0.7874 -0.4064)
			(end 0.7874 0.4064)
			(stroke
				(width 0.1524)
				(type default)
			)
			(layer "F.SilkS")
		)
		(fp_line
			(start -0.67945 0.3048)
			(end -0.67945 -0.305054)
			(stroke
				(width 0.1)
				(type default)
			)
			(layer "F.Fab")
		)
		(fp_line
			(start -0.12065 0.3048)
			(end -0.67945 0.3048)
			(stroke
				(width 0.1)
				(type default)
			)
			(layer "F.Fab")
		)
		(fp_line
			(start 0.120396 0.3048)
			(end 0.120396 0.2794)
			(stroke
				(width 0.1)
				(type default)
			)
			(layer "F.Fab")
		)
		(fp_line
			(start 0.67945 0.3048)
			(end 0.120396 0.3048)
			(stroke
				(width 0.1)
				(type default)
			)
			(layer "F.Fab")
		)
		(fp_line
			(start -0.12065 0.2794)
			(end -0.12065 0.3048)
			(stroke
				(width 0.1)
				(type default)
			)
			(layer "F.Fab")
		)
		(fp_line
			(start 0.120396 0.2794)
			(end -0.12065 0.2794)
			(stroke
				(width 0.1)
				(type default)
			)
			(layer "F.Fab")
		)
		(fp_line
			(start -0.12065 -0.2794)
			(end 0.12065 -0.2794)
			(stroke
				(width 0.1)
				(type default)
			)
			(layer "F.Fab")
		)
		(fp_line
			(start 0.12065 -0.2794)
			(end 0.12065 -0.3048)
			(stroke
				(width 0.1)
				(type default)
			)
			(layer "F.Fab")
		)
		(fp_line
			(start 0.12065 -0.3048)
			(end 0.67945 -0.3048)
			(stroke
				(width 0.1)
				(type default)
			)
			(layer "F.Fab")
		)
		(fp_line
			(start 0.67945 -0.3048)
			(end 0.67945 0.3048)
			(stroke
				(width 0.1)
				(type default)
			)
			(layer "F.Fab")
		)
		(fp_line
			(start -0.67945 -0.305054)
			(end -0.12065 -0.305054)
			(stroke
				(width 0.1)
				(type default)
			)
			(layer "F.Fab")
		)
		(fp_line
			(start -0.12065 -0.305054)
			(end -0.12065 -0.2794)
			(stroke
				(width 0.1)
				(type default)
			)
			(layer "F.Fab")
		)
		(pad "1" smd circle
			(at -0.40005 0 270)
			(size 0 0)
			(layers "F.Cu" "F.Mask" "F.Paste")
			(net "P3V3_SSD8")
		)
		(pad "2" smd circle
			(at 0.40005 0 270)
			(size 0 0)
			(layers "F.Cu" "F.Mask" "F.Paste")
			(net "DUALPORT_N_SSD8")
		)
	)
	(footprint ""
		(layer "F.Cu")
		(at 80.657446 -112.504474 90)
		(property "Reference" "C861"
			(at 0 0 90)
			(layer "F.SilkS")
			(hide yes)
			(effects
				(font
					(size 1.27 1.27)
				)
			)
		)
		(property "Value" ""
			(at 0 0 90)
			(layer "F.Fab")
			(effects
				(font
					(size 1.27 1.27)
				)
			)
		)
		(duplicate_pad_numbers_are_jumpers no)
		(fp_line
			(start 1.524 -0.762)
			(end 1.524 0.762)
			(stroke
				(width 0.1524)
				(type default)
			)
			(layer "F.SilkS")
		)
		(fp_line
			(start -1.524 -0.762)
			(end 1.524 -0.762)
			(stroke
				(width 0.1524)
				(type default)
			)
			(layer "F.SilkS")
		)
		(fp_line
			(start 1.524 0.762)
			(end -1.524 0.762)
			(stroke
				(width 0.1524)
				(type default)
			)
			(layer "F.SilkS")
		)
		(fp_line
			(start -1.524 0.762)
			(end -1.524 -0.762)
			(stroke
				(width 0.1524)
				(type default)
			)
			(layer "F.SilkS")
		)
		(fp_line
			(start 1.1049 -0.724916)
			(end -1.1049 -0.724916)
			(stroke
				(width 0.1)
				(type default)
			)
			(layer "F.Fab")
		)
		(fp_line
			(start -1.1049 -0.724916)
			(end -1.1049 0.724916)
			(stroke
				(width 0.1)
				(type default)
			)
			(layer "F.Fab")
		)
		(fp_line
			(start 1.1049 0.724916)
			(end 1.1049 -0.724916)
			(stroke
				(width 0.1)
				(type default)
			)
			(layer "F.Fab")
		)
		(fp_line
			(start -1.1049 0.724916)
			(end 1.1049 0.724916)
			(stroke
				(width 0.1)
				(type default)
			)
			(layer "F.Fab")
		)
		(pad "1" smd rect
			(at -0.889 0 270)
			(size 1.016 1.27)
			(layers "F.Cu" "F.Mask" "F.Paste")
			(net "P12V_NIC1")
		)
		(pad "2" smd rect
			(at 0.889 0 270)
			(size 1.016 1.27)
			(layers "F.Cu" "F.Mask" "F.Paste")
			(net "GND")
		)
	)
	(footprint ""
		(layer "F.Cu")
		(at 6.297168 -274.861274 90)
		(property "Reference" "R770"
			(at 0 0 90)
			(layer "F.SilkS")
			(hide yes)
			(effects
				(font
					(size 1.27 1.27)
				)
			)
		)
		(property "Value" ""
			(at 0 0 90)
			(layer "F.Fab")
			(effects
				(font
					(size 1.27 1.27)
				)
			)
		)
		(duplicate_pad_numbers_are_jumpers no)
		(fp_line
			(start 3.937508 -1.8796)
			(end -3.937508 -1.8796)
			(stroke
				(width 0.1524)
				(type default)
			)
			(layer "F.SilkS")
		)
		(fp_line
			(start -3.937508 -1.8796)
			(end -3.937508 1.8796)
			(stroke
				(width 0.1524)
				(type default)
			)
			(layer "F.SilkS")
		)
		(fp_line
			(start 3.937508 1.8796)
			(end 3.937508 -1.8796)
			(stroke
				(width 0.1524)
				(type default)
			)
			(layer "F.SilkS")
		)
		(fp_line
			(start -3.937508 1.8796)
			(end 3.937508 1.8796)
			(stroke
				(width 0.1524)
				(type default)
			)
			(layer "F.SilkS")
		)
		(fp_line
			(start 3.275076 -1.674876)
			(end -3.275076 -1.674876)
			(stroke
				(width 0.1)
				(type default)
			)
			(layer "F.Fab")
		)
		(fp_line
			(start -3.275076 -1.674876)
			(end -3.275076 1.674876)
			(stroke
				(width 0.1)
				(type default)
			)
			(layer "F.Fab")
		)
		(fp_line
			(start 3.275076 1.674876)
			(end 3.275076 -1.674876)
			(stroke
				(width 0.1)
				(type default)
			)
			(layer "F.Fab")
		)
		(fp_line
			(start -3.275076 1.674876)
			(end 3.275076 1.674876)
			(stroke
				(width 0.1)
				(type default)
			)
			(layer "F.Fab")
		)
		(pad "1" smd rect
			(at -2.350008 0 90)
			(size 2.921 3.5052)
			(layers "F.Cu" "F.Mask" "F.Paste")
			(net "P1V25_PEX0")
		)
		(pad "2" smd rect
			(at 2.350008 0 90)
			(size 2.921 3.5052)
			(layers "F.Cu" "F.Mask" "F.Paste")
			(net "P1V25_PEX0_R")
		)
	)
)
